FILE_TYPE = CONNECTIVITY;
{Allegro Design Entry HDL 17.4-2019 S026 (4007227) 1/17/2022}
"PAGE_NUMBER" = 423;
0"NC";
END.
